(kicad_pcb
	(version 20260206)
	(generator "pcbnew")
	(generator_version "10.0")
	(general
		(thickness 1.6)
		(legacy_teardrops no)
	)
	(paper "A4")
	(title_block
		(title "04192023_DAF0TMB3IC0_F0TG_MB_C_brd_V02_OCP.brd")
		(comment 1 "Grand Teton / footprints 1532-1536 of 8354")
	)
	(layers
		(0 "F.Cu" signal "TOP")
		(4 "In1.Cu" signal "GND")
		(6 "In2.Cu" signal "IN1")
		(8 "In3.Cu" signal "GND1")
		(10 "In4.Cu" signal "IN2")
		(12 "In5.Cu" signal "GND2")
		(14 "In6.Cu" signal "IN3")
		(16 "In7.Cu" signal "GND3")
		(18 "In8.Cu" signal "VCC")
		(20 "In9.Cu" signal "VCC1")
		(22 "In10.Cu" signal "GND4")
		(24 "In11.Cu" signal "IN4")
		(26 "In12.Cu" signal "GND5")
		(28 "In13.Cu" signal "IN5")
		(30 "In14.Cu" signal "GND6")
		(32 "In15.Cu" signal "IN6")
		(34 "In16.Cu" signal "GND7")
		(2 "B.Cu" signal "BOTTOM")
		(9 "F.Adhes" user "F.Adhesive")
		(11 "B.Adhes" user "B.Adhesive")
		(13 "F.Paste" user "Package Geometry/Pastemask Top")
		(15 "B.Paste" user "Package Geometry/Pastemask Bottom")
		(5 "F.SilkS" user "Ref Des/Silkscreen Top")
		(7 "B.SilkS" user "Ref Des/Silkscreen Bottom")
		(1 "F.Mask" user "Board Geometry/Soldermask Top")
		(3 "B.Mask" user "Board Geometry/Soldermask Bottom")
		(17 "Dwgs.User" user "User.Drawings")
		(19 "Cmts.User" user "User.Comments")
		(21 "Eco1.User" user "User.Eco1")
		(23 "Eco2.User" user "User.Eco2")
		(25 "Edge.Cuts" user "Board Geometry/Outline")
		(27 "Margin" user)
		(31 "F.CrtYd" user "Package Geometry/Place Bound Top")
		(29 "B.CrtYd" user "Package Geometry/Place Bound Bottom")
		(35 "F.Fab" user "Ref Des/Assembly Top")
		(33 "B.Fab" user "Ref Des/Assembly Bottom")
	)
	(footprint ""
		(layer "F.Cu")
		(at 344.505026 -416.899344 -90)
		(property "Reference" "C6527"
			(at 0 0 270)
			(layer "F.SilkS")
			(hide yes)
			(effects
				(font
					(size 1.27 1.27)
				)
			)
		)
		(property "Value" ""
			(at 0 0 270)
			(layer "F.Fab")
			(effects
				(font
					(size 1.27 1.27)
				)
			)
		)
		(duplicate_pad_numbers_are_jumpers no)
		(fp_line
			(start -0.299974 0.150114)
			(end -0.299974 -0.150114)
			(stroke
				(width 0.1)
				(type default)
			)
			(layer "F.Fab")
		)
		(fp_line
			(start 0.299974 0.150114)
			(end -0.299974 0.150114)
			(stroke
				(width 0.1)
				(type default)
			)
			(layer "F.Fab")
		)
		(fp_line
			(start -0.299974 -0.150114)
			(end 0.299974 -0.150114)
			(stroke
				(width 0.1)
				(type default)
			)
			(layer "F.Fab")
		)
		(fp_line
			(start 0.299974 -0.150114)
			(end 0.299974 0.150114)
			(stroke
				(width 0.1)
				(type default)
			)
			(layer "F.Fab")
		)
		(pad "1" smd rect
			(at -0.2667 0 270)
			(size 0.3048 0.381)
			(layers "F.Cu" "F.Mask" "F.Paste")
			(net "P5E_CPU0_P0_TX_BUF_C_DP<13>")
		)
		(pad "2" smd rect
			(at 0.2667 0 270)
			(size 0.3048 0.381)
			(layers "F.Cu" "F.Mask" "F.Paste")
			(net "P5E_CPU0_P0_TX_BUF_DP<13>")
		)
	)
	(footprint ""
		(layer "F.Cu")
		(at 102.390194 -385.09448 180)
		(property "Reference" "R664"
			(at 0 0 180)
			(layer "F.SilkS")
			(hide yes)
			(effects
				(font
					(size 1.27 1.27)
				)
			)
		)
		(property "Value" ""
			(at 0 0 180)
			(layer "F.Fab")
			(effects
				(font
					(size 1.27 1.27)
				)
			)
		)
		(duplicate_pad_numbers_are_jumpers no)
		(fp_line
			(start 0.7874 0.4064)
			(end -0.7874 0.4064)
			(stroke
				(width 0.1524)
				(type default)
			)
			(layer "F.SilkS")
		)
		(fp_line
			(start 0.7874 -0.4064)
			(end 0.7874 0.4064)
			(stroke
				(width 0.1524)
				(type default)
			)
			(layer "F.SilkS")
		)
		(fp_line
			(start -0.7874 0.4064)
			(end -0.7874 -0.4064)
			(stroke
				(width 0.1524)
				(type default)
			)
			(layer "F.SilkS")
		)
		(fp_line
			(start -0.7874 -0.4064)
			(end 0.7874 -0.4064)
			(stroke
				(width 0.1524)
				(type default)
			)
			(layer "F.SilkS")
		)
		(fp_line
			(start 0.67945 0.3048)
			(end 0.120396 0.3048)
			(stroke
				(width 0.1)
				(type default)
			)
			(layer "F.Fab")
		)
		(fp_line
			(start 0.67945 -0.3048)
			(end 0.67945 0.3048)
			(stroke
				(width 0.1)
				(type default)
			)
			(layer "F.Fab")
		)
		(fp_line
			(start 0.12065 -0.2794)
			(end 0.12065 -0.3048)
			(stroke
				(width 0.1)
				(type default)
			)
			(layer "F.Fab")
		)
		(fp_line
			(start 0.12065 -0.3048)
			(end 0.67945 -0.3048)
			(stroke
				(width 0.1)
				(type default)
			)
			(layer "F.Fab")
		)
		(fp_line
			(start 0.120396 0.3048)
			(end 0.120396 0.2794)
			(stroke
				(width 0.1)
				(type default)
			)
			(layer "F.Fab")
		)
		(fp_line
			(start 0.120396 0.2794)
			(end -0.12065 0.2794)
			(stroke
				(width 0.1)
				(type default)
			)
			(layer "F.Fab")
		)
		(fp_line
			(start -0.12065 0.3048)
			(end -0.67945 0.3048)
			(stroke
				(width 0.1)
				(type default)
			)
			(layer "F.Fab")
		)
		(fp_line
			(start -0.12065 0.2794)
			(end -0.12065 0.3048)
			(stroke
				(width 0.1)
				(type default)
			)
			(layer "F.Fab")
		)
		(fp_line
			(start -0.12065 -0.2794)
			(end 0.12065 -0.2794)
			(stroke
				(width 0.1)
				(type default)
			)
			(layer "F.Fab")
		)
		(fp_line
			(start -0.12065 -0.305054)
			(end -0.12065 -0.2794)
			(stroke
				(width 0.1)
				(type default)
			)
			(layer "F.Fab")
		)
		(fp_line
			(start -0.67945 0.3048)
			(end -0.67945 -0.305054)
			(stroke
				(width 0.1)
				(type default)
			)
			(layer "F.Fab")
		)
		(fp_line
			(start -0.67945 -0.305054)
			(end -0.12065 -0.305054)
			(stroke
				(width 0.1)
				(type default)
			)
			(layer "F.Fab")
		)
		(pad "1" smd rect
			(at -0.40005 0)
			(size 0.4572 0.508)
			(layers "F.Cu" "F.Mask" "F.Paste")
			(net "P1V8_CPU1_RT1_1A_1D")
		)
		(pad "2" smd rect
			(at 0.40005 0)
			(size 0.4572 0.508)
			(layers "F.Cu" "F.Mask" "F.Paste")
			(net "P1V8_CPU1_RT1_1A")
		)
	)
	(footprint ""
		(layer "F.Cu")
		(at 367.157 -413.639 90)
		(property "Reference" "R4180"
			(at 0 0 90)
			(layer "F.SilkS")
			(hide yes)
			(effects
				(font
					(size 1.27 1.27)
				)
			)
		)
		(property "Value" ""
			(at 0 0 90)
			(layer "F.Fab")
			(effects
				(font
					(size 1.27 1.27)
				)
			)
		)
		(duplicate_pad_numbers_are_jumpers no)
		(fp_line
			(start 0.7874 -0.4064)
			(end 0.7874 0.4064)
			(stroke
				(width 0.1524)
				(type default)
			)
			(layer "F.SilkS")
		)
		(fp_line
			(start -0.7874 -0.4064)
			(end 0.7874 -0.4064)
			(stroke
				(width 0.1524)
				(type default)
			)
			(layer "F.SilkS")
		)
		(fp_line
			(start 0.7874 0.4064)
			(end -0.7874 0.4064)
			(stroke
				(width 0.1524)
				(type default)
			)
			(layer "F.SilkS")
		)
		(fp_line
			(start -0.7874 0.4064)
			(end -0.7874 -0.4064)
			(stroke
				(width 0.1524)
				(type default)
			)
			(layer "F.SilkS")
		)
		(fp_line
			(start -0.12065 -0.305054)
			(end -0.12065 -0.2794)
			(stroke
				(width 0.1)
				(type default)
			)
			(layer "F.Fab")
		)
		(fp_line
			(start -0.67945 -0.305054)
			(end -0.12065 -0.305054)
			(stroke
				(width 0.1)
				(type default)
			)
			(layer "F.Fab")
		)
		(fp_line
			(start 0.67945 -0.3048)
			(end 0.67945 0.3048)
			(stroke
				(width 0.1)
				(type default)
			)
			(layer "F.Fab")
		)
		(fp_line
			(start 0.12065 -0.3048)
			(end 0.67945 -0.3048)
			(stroke
				(width 0.1)
				(type default)
			)
			(layer "F.Fab")
		)
		(fp_line
			(start 0.12065 -0.2794)
			(end 0.12065 -0.3048)
			(stroke
				(width 0.1)
				(type default)
			)
			(layer "F.Fab")
		)
		(fp_line
			(start -0.12065 -0.2794)
			(end 0.12065 -0.2794)
			(stroke
				(width 0.1)
				(type default)
			)
			(layer "F.Fab")
		)
		(fp_line
			(start 0.120396 0.2794)
			(end -0.12065 0.2794)
			(stroke
				(width 0.1)
				(type default)
			)
			(layer "F.Fab")
		)
		(fp_line
			(start -0.12065 0.2794)
			(end -0.12065 0.3048)
			(stroke
				(width 0.1)
				(type default)
			)
			(layer "F.Fab")
		)
		(fp_line
			(start 0.67945 0.3048)
			(end 0.120396 0.3048)
			(stroke
				(width 0.1)
				(type default)
			)
			(layer "F.Fab")
		)
		(fp_line
			(start 0.120396 0.3048)
			(end 0.120396 0.2794)
			(stroke
				(width 0.1)
				(type default)
			)
			(layer "F.Fab")
		)
		(fp_line
			(start -0.12065 0.3048)
			(end -0.67945 0.3048)
			(stroke
				(width 0.1)
				(type default)
			)
			(layer "F.Fab")
		)
		(fp_line
			(start -0.67945 0.3048)
			(end -0.67945 -0.305054)
			(stroke
				(width 0.1)
				(type default)
			)
			(layer "F.Fab")
		)
		(pad "1" smd circle
			(at -0.40005 0 90)
			(size 0 0)
			(layers "F.Cu" "F.Mask" "F.Paste")
			(net "SMB_LM75_0_3V3AUX_SCL")
		)
		(pad "2" smd circle
			(at 0.40005 0 90)
			(size 0 0)
			(layers "F.Cu" "F.Mask" "F.Paste")
			(net "SMB_LM75_0_3V3AUX_SCL_R1")
		)
	)
	(footprint ""
		(layer "F.Cu")
		(at 8.324596 -133.95198 -90)
		(property "Reference" "C94"
			(at 0 0 270)
			(layer "F.SilkS")
			(hide yes)
			(effects
				(font
					(size 1.27 1.27)
				)
			)
		)
		(property "Value" ""
			(at 0 0 270)
			(layer "F.Fab")
			(effects
				(font
					(size 1.27 1.27)
				)
			)
		)
		(duplicate_pad_numbers_are_jumpers no)
		(fp_line
			(start -0.7874 0.4064)
			(end -0.7874 -0.4064)
			(stroke
				(width 0.1524)
				(type default)
			)
			(layer "F.SilkS")
		)
		(fp_line
			(start 0.7874 0.4064)
			(end -0.7874 0.4064)
			(stroke
				(width 0.1524)
				(type default)
			)
			(layer "F.SilkS")
		)
		(fp_line
			(start -0.7874 -0.4064)
			(end 0.7874 -0.4064)
			(stroke
				(width 0.1524)
				(type default)
			)
			(layer "F.SilkS")
		)
		(fp_line
			(start 0.7874 -0.4064)
			(end 0.7874 0.4064)
			(stroke
				(width 0.1524)
				(type default)
			)
			(layer "F.SilkS")
		)
		(fp_line
			(start -0.67945 0.3048)
			(end -0.67945 -0.305054)
			(stroke
				(width 0.1)
				(type default)
			)
			(layer "F.Fab")
		)
		(fp_line
			(start -0.12065 0.3048)
			(end -0.67945 0.3048)
			(stroke
				(width 0.1)
				(type default)
			)
			(layer "F.Fab")
		)
		(fp_line
			(start 0.120396 0.3048)
			(end 0.120396 0.2794)
			(stroke
				(width 0.1)
				(type default)
			)
			(layer "F.Fab")
		)
		(fp_line
			(start 0.67945 0.3048)
			(end 0.120396 0.3048)
			(stroke
				(width 0.1)
				(type default)
			)
			(layer "F.Fab")
		)
		(fp_line
			(start -0.12065 0.2794)
			(end -0.12065 0.3048)
			(stroke
				(width 0.1)
				(type default)
			)
			(layer "F.Fab")
		)
		(fp_line
			(start 0.120396 0.2794)
			(end -0.12065 0.2794)
			(stroke
				(width 0.1)
				(type default)
			)
			(layer "F.Fab")
		)
		(fp_line
			(start -0.12065 -0.2794)
			(end 0.12065 -0.2794)
			(stroke
				(width 0.1)
				(type default)
			)
			(layer "F.Fab")
		)
		(fp_line
			(start 0.12065 -0.2794)
			(end 0.12065 -0.3048)
			(stroke
				(width 0.1)
				(type default)
			)
			(layer "F.Fab")
		)
		(fp_line
			(start 0.12065 -0.3048)
			(end 0.67945 -0.3048)
			(stroke
				(width 0.1)
				(type default)
			)
			(layer "F.Fab")
		)
		(fp_line
			(start 0.67945 -0.3048)
			(end 0.67945 0.3048)
			(stroke
				(width 0.1)
				(type default)
			)
			(layer "F.Fab")
		)
		(fp_line
			(start -0.67945 -0.305054)
			(end -0.12065 -0.305054)
			(stroke
				(width 0.1)
				(type default)
			)
			(layer "F.Fab")
		)
		(fp_line
			(start -0.12065 -0.305054)
			(end -0.12065 -0.2794)
			(stroke
				(width 0.1)
				(type default)
			)
			(layer "F.Fab")
		)
		(pad "1" smd circle
			(at -0.40005 0 270)
			(size 0 0)
			(layers "F.Cu" "F.Mask" "F.Paste")
			(net "CLK_GEN2_XTAL_OUT")
		)
		(pad "2" smd circle
			(at 0.40005 0 270)
			(size 0 0)
			(layers "F.Cu" "F.Mask" "F.Paste")
			(net "GND")
		)
	)
	(footprint ""
		(layer "F.Cu")
		(at 317.284608 -15.337536 -90)
		(property "Reference" "J8"
			(at -4.073398 -0.944118 0)
			(unlocked yes)
			(layer "F.SilkS")
			(effects
				(font
					(size 0.7874 0.5842)
					(thickness 0.1524)
				)
				(justify left)
			)
		)
		(property "Value" ""
			(at 0 0 270)
			(layer "F.Fab")
			(effects
				(font
					(size 1.27 1.27)
				)
			)
		)
		(duplicate_pad_numbers_are_jumpers no)
		(fp_line
			(start -2.999994 7.999984)
			(end -0.899922 7.999984)
			(stroke
				(width 0.1524)
				(type default)
			)
			(layer "F.SilkS")
		)
		(fp_line
			(start -0.899922 7.999984)
			(end 1.700022 7.999984)
			(stroke
				(width 0.1524)
				(type default)
			)
			(layer "F.SilkS")
		)
		(fp_line
			(start 1.700022 7.999984)
			(end 1.700022 -1.999996)
			(stroke
				(width 0.1524)
				(type default)
			)
			(layer "F.SilkS")
		)
		(fp_line
			(start -2.500122 7.500112)
			(end -2.500122 6.568694)
			(stroke
				(width 0.1524)
				(type default)
			)
			(layer "F.SilkS")
		)
		(fp_line
			(start 1.199896 7.500112)
			(end -2.500122 7.500112)
			(stroke
				(width 0.1524)
				(type default)
			)
			(layer "F.SilkS")
		)
		(fp_line
			(start -2.500122 5.425694)
			(end -2.500122 -1.500124)
			(stroke
				(width 0.1524)
				(type default)
			)
			(layer "F.SilkS")
		)
		(fp_line
			(start 1.199896 4.99999)
			(end 1.199896 7.500112)
			(stroke
				(width 0.1524)
				(type default)
			)
			(layer "F.SilkS")
		)
		(fp_line
			(start 1.700022 4.99999)
			(end 1.199896 4.99999)
			(stroke
				(width 0.1524)
				(type default)
			)
			(layer "F.SilkS")
		)
		(fp_line
			(start 1.199896 0.999998)
			(end 1.700022 0.999998)
			(stroke
				(width 0.1524)
				(type default)
			)
			(layer "F.SilkS")
		)
		(fp_line
			(start -2.500122 -1.500124)
			(end 1.199896 -1.500124)
			(stroke
				(width 0.1524)
				(type default)
			)
			(layer "F.SilkS")
		)
		(fp_line
			(start 1.199896 -1.500124)
			(end 1.199896 0.999998)
			(stroke
				(width 0.1524)
				(type default)
			)
			(layer "F.SilkS")
		)
		(fp_line
			(start -2.999994 -1.999996)
			(end -2.999994 7.999984)
			(stroke
				(width 0.1524)
				(type default)
			)
			(layer "F.SilkS")
		)
		(fp_line
			(start 1.700022 -1.999996)
			(end -2.999994 -1.999996)
			(stroke
				(width 0.1524)
				(type default)
			)
			(layer "F.SilkS")
		)
		(fp_poly
			(pts
				(xy 0.762 -3.731006) (xy 0 -2.207006) (xy -0.762 -3.731006)
			)
			(stroke
				(width 0)
				(type default)
			)
			(fill yes)
			(layer "F.SilkS")
		)
		(fp_line
			(start -2.999994 7.999984)
			(end -0.899922 7.999984)
			(stroke
				(width 0.1)
				(type default)
			)
			(layer "F.Fab")
		)
		(fp_line
			(start -0.899922 7.999984)
			(end 1.700022 7.999984)
			(stroke
				(width 0.1)
				(type default)
			)
			(layer "F.Fab")
		)
		(fp_line
			(start 1.700022 7.999984)
			(end 1.700022 -1.999996)
			(stroke
				(width 0.1)
				(type default)
			)
			(layer "F.Fab")
		)
		(fp_line
			(start -2.500122 7.500112)
			(end -2.500122 6.606794)
			(stroke
				(width 0.1)
				(type default)
			)
			(layer "F.Fab")
		)
		(fp_line
			(start 1.199896 7.500112)
			(end -2.500122 7.500112)
			(stroke
				(width 0.1)
				(type default)
			)
			(layer "F.Fab")
		)
		(fp_line
			(start -2.500122 6.657594)
			(end -2.500122 -1.500124)
			(stroke
				(width 0.1)
				(type default)
			)
			(layer "F.Fab")
		)
		(fp_line
			(start 1.199896 4.99999)
			(end 1.199896 7.500112)
			(stroke
				(width 0.1)
				(type default)
			)
			(layer "F.Fab")
		)
		(fp_line
			(start 1.700022 4.99999)
			(end 1.199896 4.99999)
			(stroke
				(width 0.1)
				(type default)
			)
			(layer "F.Fab")
		)
		(fp_line
			(start 1.199896 0.999998)
			(end 1.700022 0.999998)
			(stroke
				(width 0.1)
				(type default)
			)
			(layer "F.Fab")
		)
		(fp_line
			(start -2.500122 -1.500124)
			(end 1.199896 -1.500124)
			(stroke
				(width 0.1)
				(type default)
			)
			(layer "F.Fab")
		)
		(fp_line
			(start 1.199896 -1.500124)
			(end 1.199896 0.999998)
			(stroke
				(width 0.1)
				(type default)
			)
			(layer "F.Fab")
		)
		(fp_line
			(start -2.999994 -1.999996)
			(end -2.999994 7.999984)
			(stroke
				(width 0.1)
				(type default)
			)
			(layer "F.Fab")
		)
		(fp_line
			(start 1.700022 -1.999996)
			(end -2.999994 -1.999996)
			(stroke
				(width 0.1)
				(type default)
			)
			(layer "F.Fab")
		)
		(fp_poly
			(pts
				(xy 0 -2.207006) (xy -0.762 -3.731006) (xy 0.762 -3.731006)
			)
			(stroke
				(width 0)
				(type default)
			)
			(fill yes)
			(layer "F.Fab")
		)
		(pad "" np_thru_hole circle
			(at -1.800098 5.999988)
			(size 1.143 1.143)
			(drill 1.143)
			(layers "*.Cu" "*.Mask")
			(clearance 0.381)
			(thermal_gap 0.381)
		)
		(pad "1" thru_hole rect
			(at 0 0)
			(size 1.2192 1.2192)
			(drill 0.8128)
			(layers "*.Cu" "*.Mask")
			(remove_unused_layers no)
			(net "UART_VCC_J8")
			(clearance 0.0508)
			(thermal_gap 0.0508)
			(padstack
				(mode front_inner_back)
				(layer "Inner"
					(shape circle)
					(size 1.2192 1.2192)
					(clearance 0.0508)
				)
				(layer "B.Cu"
					(shape rect)
					(size 1.2192 1.2192)
					(clearance 0.0508)
				)
			)
		)
		(pad "2" thru_hole circle
			(at 0 1.999996)
			(size 1.2192 1.2192)
			(drill 0.8128)
			(layers "*.Cu" "*.Mask")
			(remove_unused_layers no)
			(net "UART_CPU0_SCM_LVC3_UART1_R_RX")
			(clearance 0.0508)
			(thermal_gap 0.0508)
		)
		(pad "3" thru_hole circle
			(at 0 3.999992)
			(size 1.2192 1.2192)
			(drill 0.8128)
			(layers "*.Cu" "*.Mask")
			(remove_unused_layers no)
			(net "UART_CPU0_SCM_LVC3_UART1_TX")
			(clearance 0.0508)
			(thermal_gap 0.0508)
		)
		(pad "4" thru_hole circle
			(at 0 5.999988)
			(size 1.2192 1.2192)
			(drill 0.8128)
			(layers "*.Cu" "*.Mask")
			(remove_unused_layers no)
			(net "GND")
			(clearance 0.0508)
			(thermal_gap 0.0508)
		)
		(zone
			(layers "F.Cu" "B.Cu" "In1.Cu" "In2.Cu" "In3.Cu" "In4.Cu" "In5.Cu" "In6.Cu"
				"In7.Cu" "In8.Cu" "In9.Cu" "In10.Cu" "In11.Cu" "In12.Cu" "In13.Cu" "In14.Cu"
				"In15.Cu" "In16.Cu"
			)
			(hatch none 0.5)
			(connect_pads
				(clearance 0)
			)
			(min_thickness 0.25)
			(keepout
				(tracks not_allowed)
				(vias allowed)
				(pads allowed)
				(copperpour not_allowed)
				(footprints allowed)
			)
			(placement
				(enabled no)
				(sheetname "")
			)
			(fill
				(thermal_gap 0.5)
				(thermal_bridge_width 0.5)
				(island_removal_mode 0)
			)
			(polygon
				(pts
					(arc
						(start 310.266334 -17.126458)
						(mid 310.565401 -17.848471)
						(end 311.287414 -18.147538)
					)
					(arc
						(start 311.287414 -18.147538)
						(mid 312.295794 -17.139158)
						(end 311.287414 -16.130778)
					)
					(arc
						(start 311.262014 -16.130778)
						(mid 310.557962 -16.422406)
						(end 310.266334 -17.126458)
					)
				)
			)
		)
	)
)
